(kicad_pcb
	(version 20260206)
	(generator "pcbnew")
	(generator_version "10.0")
	(general
		(thickness 1.6)
		(legacy_teardrops no)
	)
	(paper "A4")
	(title_block
		(title "Bryce Canyon_R.DPB_16317-1_OCP.brd")
		(comment 1 "Bryce Canyon / footprints 854-859 of 2099")
	)
	(layers
		(0 "F.Cu" signal "TOP")
		(4 "In1.Cu" signal "L2GND")
		(6 "In2.Cu" signal "L3")
		(8 "In3.Cu" signal "L4VCC")
		(10 "In4.Cu" signal "L5VCC")
		(12 "In5.Cu" signal "L6")
		(14 "In6.Cu" signal "L7GND")
		(2 "B.Cu" signal "BOTTOM")
		(9 "F.Adhes" user "F.Adhesive")
		(11 "B.Adhes" user "B.Adhesive")
		(13 "F.Paste" user "Package Geometry/Pastemask Top")
		(15 "B.Paste" user "Package Geometry/Pastemask Bottom")
		(5 "F.SilkS" user "Ref Des/Silkscreen Top")
		(7 "B.SilkS" user "Ref Des/Silkscreen Bottom")
		(1 "F.Mask" user "Board Geometry/Soldermask Top")
		(3 "B.Mask" user "Board Geometry/Soldermask Bottom")
		(17 "Dwgs.User" user "User.Drawings")
		(19 "Cmts.User" user "User.Comments")
		(21 "Eco1.User" user "User.Eco1")
		(23 "Eco2.User" user "User.Eco2")
		(25 "Edge.Cuts" user "Board Geometry/Outline")
		(27 "Margin" user)
		(31 "F.CrtYd" user "Package Geometry/Place Bound Top")
		(29 "B.CrtYd" user "Package Geometry/Place Bound Bottom")
		(35 "F.Fab" user "Ref Des/Assembly Top")
		(33 "B.Fab" user "Ref Des/Assembly Bottom")
	)
	(footprint ""
		(layer "F.Cu")
		(at 168.275 -377.19 -90)
		(property "Reference" "Q193"
			(at 0 0 270)
			(layer "F.SilkS")
			(hide yes)
			(effects
				(font
					(size 1.27 1.27)
				)
			)
		)
		(property "Value" "MMBT3904-3-GP"
			(at 0.10287 -10.29843 270)
			(unlocked yes)
			(layer "F.Fab")
			(hide yes)
			(effects
				(font
					(size 1.016 1.016)
					(thickness 0.1524)
				)
			)
		)
		(property "Device Type" "SOT23CBE2D4H44"
			(at 0.10287 -12.20343 270)
			(unlocked yes)
			(layer "F.Fab")
			(hide yes)
			(effects
				(font
					(size 1.016 1.016)
					(thickness 0.1524)
				)
			)
		)
		(duplicate_pad_numbers_are_jumpers no)
		(fp_line
			(start -1.651 1.778)
			(end 1.651 1.778)
			(stroke
				(width 0.1524)
				(type default)
			)
			(layer "F.SilkS")
		)
		(fp_line
			(start 1.651 1.778)
			(end 1.651 -1.778)
			(stroke
				(width 0.1524)
				(type default)
			)
			(layer "F.SilkS")
		)
		(fp_line
			(start -1.651 -1.778)
			(end -1.651 1.778)
			(stroke
				(width 0.1524)
				(type default)
			)
			(layer "F.SilkS")
		)
		(fp_line
			(start 1.651 -1.778)
			(end -1.651 -1.778)
			(stroke
				(width 0.1524)
				(type default)
			)
			(layer "F.SilkS")
		)
		(fp_poly
			(pts
				(xy -1.778 1.8796) (xy -1.778 -1.8796) (xy 1.778 -1.8796) (xy 1.778 1.8796)
			)
			(stroke
				(width 0)
				(type default)
			)
			(fill no)
			(layer "F.CrtYd")
		)
		(fp_poly
			(pts
				(xy -1.778 1.8796) (xy -1.778 -1.8796) (xy 1.778 -1.8796) (xy 1.778 1.8796)
			)
			(stroke
				(width 0)
				(type default)
			)
			(fill no)
			(layer "F.Fab")
		)
		(pad "B" smd custom
			(at -0.98425 0.9525 270)
			(size 0.1905 0.1905)
			(layers "F.Cu" "F.Mask" "F.Paste")
			(net "MB0_TEMP_B")
			(options
				(clearance outline)
				(anchor circle)
			)
			(primitives
				(gr_poly
					(pts
						(arc
							(start -0.1778 0.5715)
							(mid -0.321484 0.511984)
							(end -0.381 0.3683)
						)
						(arc
							(start -0.381 -0.3683)
							(mid -0.321484 -0.511984)
							(end -0.1778 -0.5715)
						)
						(arc
							(start 0.1778 -0.5715)
							(mid 0.321484 -0.511984)
							(end 0.381 -0.3683)
						)
						(arc
							(start 0.381 0.3683)
							(mid 0.321484 0.511984)
							(end 0.1778 0.5715)
						)
					)
					(width 0)
					(fill yes)
				)
			)
		)
		(pad "C" smd custom
			(at 0 -0.9525 270)
			(size 0.1905 0.1905)
			(layers "F.Cu" "F.Mask" "F.Paste")
			(net "MB0_TEMP_B")
			(options
				(clearance outline)
				(anchor circle)
			)
			(primitives
				(gr_poly
					(pts
						(arc
							(start -0.1778 0.5715)
							(mid -0.321484 0.511984)
							(end -0.381 0.3683)
						)
						(arc
							(start -0.381 -0.3683)
							(mid -0.321484 -0.511984)
							(end -0.1778 -0.5715)
						)
						(arc
							(start 0.1778 -0.5715)
							(mid 0.321484 -0.511984)
							(end 0.381 -0.3683)
						)
						(arc
							(start 0.381 0.3683)
							(mid 0.321484 0.511984)
							(end 0.1778 0.5715)
						)
					)
					(width 0)
					(fill yes)
				)
			)
		)
		(pad "E" smd custom
			(at 0.98425 0.9525 270)
			(size 0.1905 0.1905)
			(layers "F.Cu" "F.Mask" "F.Paste")
			(net "MB0_TEMP_E")
			(options
				(clearance outline)
				(anchor circle)
			)
			(primitives
				(gr_poly
					(pts
						(arc
							(start -0.1778 0.5715)
							(mid -0.321484 0.511984)
							(end -0.381 0.3683)
						)
						(arc
							(start -0.381 -0.3683)
							(mid -0.321484 -0.511984)
							(end -0.1778 -0.5715)
						)
						(arc
							(start 0.1778 -0.5715)
							(mid 0.321484 -0.511984)
							(end 0.381 -0.3683)
						)
						(arc
							(start 0.381 0.3683)
							(mid 0.321484 0.511984)
							(end 0.1778 0.5715)
						)
					)
					(width 0)
					(fill yes)
				)
			)
		)
	)
	(footprint ""
		(layer "F.Cu")
		(at 264.328402 -372.399814)
		(property "Reference" "R1063"
			(at 0 0 0)
			(layer "F.SilkS")
			(hide yes)
			(effects
				(font
					(size 1.27 1.27)
				)
			)
		)
		(property "Value" "10KR2F-2-GP"
			(at 0.064008 -3.993896 0)
			(unlocked yes)
			(layer "F.Fab")
			(hide yes)
			(effects
				(font
					(size 1.016 1.016)
					(thickness 0.1524)
				)
			)
		)
		(property "Device Type" "R402H16"
			(at 0.064008 -5.517896 0)
			(unlocked yes)
			(layer "F.Fab")
			(hide yes)
			(effects
				(font
					(size 1.016 1.016)
					(thickness 0.1524)
				)
			)
		)
		(duplicate_pad_numbers_are_jumpers no)
		(fp_line
			(start -0.508 -0.9398)
			(end -0.508 0.9398)
			(stroke
				(width 0.1524)
				(type default)
			)
			(layer "F.SilkS")
		)
		(fp_line
			(start 0.508 -0.9398)
			(end -0.508 -0.9398)
			(stroke
				(width 0.1524)
				(type default)
			)
			(layer "F.SilkS")
		)
		(fp_rect
			(start -0.508 0.9398)
			(end 0.508 -0.9398)
			(stroke
				(width 0)
				(type default)
			)
			(fill no)
			(layer "F.CrtYd")
		)
		(fp_rect
			(start -0.508 0.9398)
			(end 0.508 -0.9398)
			(stroke
				(width 0)
				(type default)
			)
			(fill no)
			(layer "F.Fab")
		)
		(pad "1" smd custom
			(at 0 -0.4445)
			(size 0.1397 0.1397)
			(layers "F.Cu" "F.Mask" "F.Paste")
			(net "P3V3_IN")
			(options
				(clearance outline)
				(anchor circle)
			)
			(primitives
				(gr_poly
					(pts
						(arc
							(start -0.1778 -0.2794)
							(mid -0.249642 -0.249642)
							(end -0.2794 -0.1778)
						)
						(arc
							(start -0.2794 0.1778)
							(mid -0.249642 0.249642)
							(end -0.1778 0.2794)
						)
						(arc
							(start 0.1778 0.2794)
							(mid 0.249642 0.249642)
							(end 0.2794 0.1778)
						)
						(arc
							(start 0.2794 -0.1778)
							(mid 0.249642 -0.249642)
							(end 0.1778 -0.2794)
						)
					)
					(width 0)
					(fill yes)
				)
			)
		)
		(pad "2" smd custom
			(at 0 0.4445)
			(size 0.1397 0.1397)
			(layers "F.Cu" "F.Mask" "F.Paste")
			(net "DRAWER_CLOSED_N")
			(options
				(clearance outline)
				(anchor circle)
			)
			(primitives
				(gr_poly
					(pts
						(arc
							(start -0.1778 -0.2794)
							(mid -0.249642 -0.249642)
							(end -0.2794 -0.1778)
						)
						(arc
							(start -0.2794 0.1778)
							(mid -0.249642 0.249642)
							(end -0.1778 0.2794)
						)
						(arc
							(start 0.1778 0.2794)
							(mid 0.249642 0.249642)
							(end 0.2794 0.1778)
						)
						(arc
							(start 0.2794 -0.1778)
							(mid 0.249642 -0.249642)
							(end 0.1778 -0.2794)
						)
					)
					(width 0)
					(fill yes)
				)
			)
		)
	)
	(footprint ""
		(layer "F.Cu")
		(at 414.042352 -245.016274 90)
		(property "Reference" "VIA19"
			(at 0 0 90)
			(layer "F.SilkS")
			(hide yes)
			(effects
				(font
					(size 1.27 1.27)
				)
			)
		)
		(property "Value" "100OHM-8L-2D36MM-L18-GP"
			(at 3.8989 0.5715 90)
			(unlocked yes)
			(layer "F.Fab")
			(hide yes)
			(effects
				(font
					(size 1.016 1.016)
					(thickness 0.1524)
				)
			)
		)
		(property "Device Type" "VIA-PCIE-4P-414097"
			(at 3.8989 -0.9525 90)
			(unlocked yes)
			(layer "F.Fab")
			(hide yes)
			(effects
				(font
					(size 1.016 1.016)
					(thickness 0.1524)
				)
			)
		)
		(duplicate_pad_numbers_are_jumpers no)
		(fp_rect
			(start -2.0701 0.4826)
			(end 2.0701 -0.4826)
			(stroke
				(width 0)
				(type default)
			)
			(fill no)
			(layer "F.CrtYd")
		)
		(fp_rect
			(start -2.0701 0.4826)
			(end 2.0701 -0.4826)
			(stroke
				(width 0)
				(type default)
			)
			(fill no)
			(layer "F.Fab")
		)
		(pad "1" thru_hole circle
			(at -1.5875 0 90)
			(size 0.508 0.508)
			(drill 0.254)
			(layers "*.Cu" "*.Mask")
			(remove_unused_layers no)
			(net "GND")
			(clearance 0.2286)
			(thermal_gap 0.2286)
		)
		(pad "2" thru_hole circle
			(at -0.5715 0 90)
			(size 0.508 0.508)
			(drill 0.254)
			(layers "*.Cu" "*.Mask")
			(remove_unused_layers no)
			(net "PHY_SCC_B_TO_DRV_B_9_DP")
			(clearance 0.2286)
			(thermal_gap 0.2286)
		)
		(pad "3" thru_hole circle
			(at 0.5715 0 90)
			(size 0.508 0.508)
			(drill 0.254)
			(layers "*.Cu" "*.Mask")
			(remove_unused_layers no)
			(net "PHY_SCC_B_TO_DRV_B_9_DN")
			(clearance 0.2286)
			(thermal_gap 0.2286)
		)
		(pad "4" thru_hole circle
			(at 1.5875 0 90)
			(size 0.508 0.508)
			(drill 0.254)
			(layers "*.Cu" "*.Mask")
			(remove_unused_layers no)
			(net "GND")
			(clearance 0.2286)
			(thermal_gap 0.2286)
		)
	)
	(footprint ""
		(layer "F.Cu")
		(at 46.482 -260.858)
		(property "Reference" "Q4"
			(at 0 0 0)
			(layer "F.SilkS")
			(hide yes)
			(effects
				(font
					(size 1.27 1.27)
				)
			)
		)
		(property "Value" "AO4407AL-GP"
			(at -3.707384 -1.5367 0)
			(unlocked yes)
			(layer "F.Fab")
			(hide yes)
			(effects
				(font
					(size 1.016 1.016)
					(thickness 0.1524)
				)
			)
		)
		(property "Device Type" "SOIC8H69"
			(at -3.707384 -3.0607 0)
			(unlocked yes)
			(layer "F.Fab")
			(hide yes)
			(effects
				(font
					(size 1.016 1.016)
					(thickness 0.1524)
				)
			)
		)
		(duplicate_pad_numbers_are_jumpers no)
		(fp_line
			(start -2.7432 -1.4224)
			(end -2.7432 1.4224)
			(stroke
				(width 0.1524)
				(type default)
			)
			(layer "F.SilkS")
		)
		(fp_line
			(start -2.7432 1.4224)
			(end -2.6416 1.4224)
			(stroke
				(width 0.1524)
				(type default)
			)
			(layer "F.SilkS")
		)
		(fp_line
			(start -2.7432 1.4224)
			(end 2.1336 1.4224)
			(stroke
				(width 0.1524)
				(type default)
			)
			(layer "F.SilkS")
		)
		(fp_line
			(start -2.7178 -0.508)
			(end -2.1844 -0.0508)
			(stroke
				(width 0.1524)
				(type default)
			)
			(layer "F.SilkS")
		)
		(fp_line
			(start -2.6289 3.4417)
			(end -2.6289 1.4732)
			(stroke
				(width 0.381)
				(type default)
			)
			(layer "F.SilkS")
		)
		(fp_line
			(start -2.1844 -0.0508)
			(end -2.7178 0.508)
			(stroke
				(width 0.1524)
				(type default)
			)
			(layer "F.SilkS")
		)
		(fp_line
			(start 2.1336 -1.4224)
			(end -2.7432 -1.4224)
			(stroke
				(width 0.1524)
				(type default)
			)
			(layer "F.SilkS")
		)
		(fp_line
			(start 2.1336 1.4224)
			(end 2.1336 -1.4224)
			(stroke
				(width 0.1524)
				(type default)
			)
			(layer "F.SilkS")
		)
		(fp_poly
			(pts
				(xy -2.2098 -1.4224) (xy -2.2098 1.4224) (xy 2.2098 1.4224) (xy 2.2098 -1.4224)
			)
			(stroke
				(width 0)
				(type default)
			)
			(fill yes)
			(layer "F.SilkS")
		)
		(fp_rect
			(start -2.450084 2.999994)
			(end 2.450084 -2.999994)
			(stroke
				(width 0)
				(type default)
			)
			(fill no)
			(layer "F.CrtYd")
		)
		(fp_poly
			(pts
				(xy -2.8194 3.6322) (xy -2.8194 -3.6322) (xy 2.8194 -3.6322) (xy 2.8194 1.18364) (xy 2.450084 1.18364)
				(xy 2.450084 -2.999994) (xy -2.450084 -2.999994) (xy -2.450084 2.999994) (xy 2.450084 2.999994)
				(xy 2.450084 1.18618) (xy 2.8194 1.18618) (xy 2.8194 3.6322)
			)
			(stroke
				(width 0)
				(type default)
			)
			(fill no)
			(layer "F.CrtYd")
		)
		(fp_rect
			(start -2.8194 3.6322)
			(end 2.8194 -3.6322)
			(stroke
				(width 0)
				(type default)
			)
			(fill no)
			(layer "F.Fab")
		)
		(pad "1" smd rect
			(at -1.905 2.54)
			(size 0.635 1.651)
			(layers "F.Cu" "F.Mask" "F.Paste")
			(net "P12V_B")
		)
		(pad "2" smd rect
			(at -0.635 2.54)
			(size 0.635 1.651)
			(layers "F.Cu" "F.Mask" "F.Paste")
			(net "P12V_B")
		)
		(pad "3" smd rect
			(at 0.635 2.54)
			(size 0.635 1.651)
			(layers "F.Cu" "F.Mask" "F.Paste")
			(net "P12V_B")
		)
		(pad "4" smd rect
			(at 1.905 2.54)
			(size 0.635 1.651)
			(layers "F.Cu" "F.Mask" "F.Paste")
			(net "SW_HDD_N1")
		)
		(pad "5" smd rect
			(at 1.905 -2.54)
			(size 0.635 1.651)
			(layers "F.Cu" "F.Mask" "F.Paste")
			(net "P12V_HDD1")
		)
		(pad "6" smd rect
			(at 0.635 -2.54)
			(size 0.635 1.651)
			(layers "F.Cu" "F.Mask" "F.Paste")
			(net "P12V_HDD1")
		)
		(pad "7" smd rect
			(at -0.635 -2.54)
			(size 0.635 1.651)
			(layers "F.Cu" "F.Mask" "F.Paste")
			(net "P12V_HDD1")
		)
		(pad "8" smd rect
			(at -1.905 -2.54)
			(size 0.635 1.651)
			(layers "F.Cu" "F.Mask" "F.Paste")
			(net "P12V_HDD1")
		)
	)
	(footprint ""
		(layer "F.Cu")
		(at 114.7826 -263.779 -90)
		(property "Reference" "C69"
			(at 0 0 270)
			(layer "F.SilkS")
			(hide yes)
			(effects
				(font
					(size 1.27 1.27)
				)
			)
		)
		(property "Value" "SC1U16V3KX-5GP"
			(at 0 -2.8194 270)
			(unlocked yes)
			(layer "F.Fab")
			(hide yes)
			(effects
				(font
					(size 1.016 1.016)
					(thickness 0.1524)
				)
			)
		)
		(property "Device Type" "C603H36"
			(at 0 -4.3434 270)
			(unlocked yes)
			(layer "F.Fab")
			(hide yes)
			(effects
				(font
					(size 1.016 1.016)
					(thickness 0.1524)
				)
			)
		)
		(duplicate_pad_numbers_are_jumpers no)
		(fp_line
			(start 0.508 0)
			(end -0.508 0)
			(stroke
				(width 0.2032)
				(type default)
			)
			(layer "F.SilkS")
		)
		(fp_rect
			(start -0.5842 1.3335)
			(end 0.5842 -1.3335)
			(stroke
				(width 0)
				(type default)
			)
			(fill no)
			(layer "F.CrtYd")
		)
		(fp_rect
			(start -0.5842 1.3335)
			(end 0.5842 -1.3335)
			(stroke
				(width 0)
				(type default)
			)
			(fill no)
			(layer "F.Fab")
		)
		(pad "1" smd custom
			(at 0 -0.762 270)
			(size 0.2159 0.2159)
			(layers "F.Cu" "F.Mask" "F.Paste")
			(net "P5V_HDD3")
			(options
				(clearance outline)
				(anchor circle)
			)
			(primitives
				(gr_poly
					(pts
						(arc
							(start -0.3302 -0.4318)
							(mid -0.402042 -0.402042)
							(end -0.4318 -0.3302)
						)
						(arc
							(start -0.4318 0.3302)
							(mid -0.402042 0.402042)
							(end -0.3302 0.4318)
						)
						(arc
							(start 0.3302 0.4318)
							(mid 0.402042 0.402042)
							(end 0.4318 0.3302)
						)
						(arc
							(start 0.4318 -0.3302)
							(mid 0.402042 -0.402042)
							(end 0.3302 -0.4318)
						)
					)
					(width 0)
					(fill yes)
				)
			)
		)
		(pad "2" smd custom
			(at 0 0.762 270)
			(size 0.2159 0.2159)
			(layers "F.Cu" "F.Mask" "F.Paste")
			(net "GND")
			(options
				(clearance outline)
				(anchor circle)
			)
			(primitives
				(gr_poly
					(pts
						(arc
							(start -0.3302 -0.4318)
							(mid -0.402042 -0.402042)
							(end -0.4318 -0.3302)
						)
						(arc
							(start -0.4318 0.3302)
							(mid -0.402042 0.402042)
							(end -0.3302 0.4318)
						)
						(arc
							(start 0.3302 0.4318)
							(mid 0.402042 0.402042)
							(end 0.4318 0.3302)
						)
						(arc
							(start 0.4318 -0.3302)
							(mid 0.402042 -0.402042)
							(end 0.3302 -0.4318)
						)
					)
					(width 0)
					(fill yes)
				)
			)
		)
	)
	(footprint ""
		(layer "F.Cu")
		(at 467.5124 -6.4008 -90)
		(property "Reference" "R135"
			(at 0 0 270)
			(layer "F.SilkS")
			(hide yes)
			(effects
				(font
					(size 1.27 1.27)
				)
			)
		)
		(property "Value" "4K7R2F-GP"
			(at 0.064008 -3.993896 270)
			(unlocked yes)
			(layer "F.Fab")
			(hide yes)
			(effects
				(font
					(size 1.016 1.016)
					(thickness 0.1524)
				)
			)
		)
		(property "Device Type" "R402H16"
			(at 0.064008 -5.517896 270)
			(unlocked yes)
			(layer "F.Fab")
			(hide yes)
			(effects
				(font
					(size 1.016 1.016)
					(thickness 0.1524)
				)
			)
		)
		(duplicate_pad_numbers_are_jumpers no)
		(fp_line
			(start -0.508 -0.9398)
			(end -0.508 0.9398)
			(stroke
				(width 0.1524)
				(type default)
			)
			(layer "F.SilkS")
		)
		(fp_line
			(start 0.508 -0.9398)
			(end -0.508 -0.9398)
			(stroke
				(width 0.1524)
				(type default)
			)
			(layer "F.SilkS")
		)
		(fp_rect
			(start -0.508 0.9398)
			(end 0.508 -0.9398)
			(stroke
				(width 0)
				(type default)
			)
			(fill no)
			(layer "F.CrtYd")
		)
		(fp_rect
			(start -0.508 0.9398)
			(end 0.508 -0.9398)
			(stroke
				(width 0)
				(type default)
			)
			(fill no)
			(layer "F.Fab")
		)
		(pad "1" smd custom
			(at 0 -0.4445 270)
			(size 0.1397 0.1397)
			(layers "F.Cu" "F.Mask" "F.Paste")
			(net "P3V3_STBY_B")
			(options
				(clearance outline)
				(anchor circle)
			)
			(primitives
				(gr_poly
					(pts
						(arc
							(start -0.1778 -0.2794)
							(mid -0.249642 -0.249642)
							(end -0.2794 -0.1778)
						)
						(arc
							(start -0.2794 0.1778)
							(mid -0.249642 0.249642)
							(end -0.1778 0.2794)
						)
						(arc
							(start 0.1778 0.2794)
							(mid 0.249642 0.249642)
							(end 0.2794 0.1778)
						)
						(arc
							(start 0.2794 -0.1778)
							(mid 0.249642 -0.249642)
							(end 0.1778 -0.2794)
						)
					)
					(width 0)
					(fill yes)
				)
			)
		)
		(pad "2" smd custom
			(at 0 0.4445 270)
			(size 0.1397 0.1397)
			(layers "F.Cu" "F.Mask" "F.Paste")
			(net "TEMP2_A1")
			(options
				(clearance outline)
				(anchor circle)
			)
			(primitives
				(gr_poly
					(pts
						(arc
							(start -0.1778 -0.2794)
							(mid -0.249642 -0.249642)
							(end -0.2794 -0.1778)
						)
						(arc
							(start -0.2794 0.1778)
							(mid -0.249642 0.249642)
							(end -0.1778 0.2794)
						)
						(arc
							(start 0.1778 0.2794)
							(mid 0.249642 0.249642)
							(end 0.2794 0.1778)
						)
						(arc
							(start 0.2794 -0.1778)
							(mid 0.249642 -0.249642)
							(end 0.1778 -0.2794)
						)
					)
					(width 0)
					(fill yes)
				)
			)
		)
	)
)
